FILE_TYPE = MACRO_DRAWING;
SET COLOR_WIRE YELLOW;
SET COLOR_PROP ORANGE;
SET COLOR_DOT WHITE;
SET COLOR_ARC YELLOW;
SET COLOR_BODY GREEN;
SET COLOR_NOTE PURPLE;
SET PROP_DISPLAY VALUE;
SET PAGE_NUMBER P7;
FORCEADD QUANTA_TITLE_BLOCK_C..1
(-100 100);
FORCEPROP 1 LAST CUSTOM_TXT_CDS <NAME_2>
J 0
(-3275 150);
FORCEPROP 1 LAST CUSTOM_TXT_CDS <NAME_1>
J 0
(-3275 275);
FORCEPROP 1 LAST CUSTOM_TXT_CDS <Q_NUMBER>
J 0
(-1503 203);
DISPLAY 1.212766 (-1503 203);
FORCEPROP 1 LAST CUSTOM_TXT_CDS <Q_PROJ>
J 0
(-2482 202);
DISPLAY 1.212766 (-2482 202);
FORCEPROP 1 LAST CUSTOM_TXT_CDS <Q_REV>
J 0
(-284 203);
DISPLAY 1.212766 (-284 203);
FORCEPROP 1 LAST CUSTOM_TXT_CDS <CON_LAST_MODIFIED>
J 0
(-1985 115);
DISPLAY 0.978723 (-1985 115);
FORCEPROP 1 LAST CUSTOM_TXT_CDS <CON_PAGE_NUM> OF <CON_TOTAL_PAGES>
J 0
(-546 118);
DISPLAY 0.978723 (-546 118);
FORCEPROP 1 LAST Q_DEPT BU9
J 1
(-3863 149);
DISPLAY 1.957447 (-3863 149);
PAINT GREEN (-3863 149);
FORCEPROP 1 LAST Q_TITLE BLOCK DIAGRAM - CLOCK
J 0
(-9425 125);
DISPLAY 2.446809 (-9425 125);
PAINT GREEN (-9425 125);
FORCEPROP 0 LAST CDS_CON_LAST_MODIFIED Wed Jul 21 11:34:14 2021
J 0
(-1985 115);
DISPLAY INVISIBLE (-1985 115);
FORCEPROP 1 LAST CDS_LMAN_SYM_OUTLINE -9475,6775,100,-125
J 0
(-100 100);
DISPLAY 0.468085 (-100 100);
PAINT GREEN (-100 100);
DISPLAY INVISIBLE (-100 100);
FORCEPROP 2 LAST CDS_LIB pure_quanta
J 0
(-100 100);
DISPLAY INVISIBLE (-100 100);
FORCEPROP 2 LAST PAGE_BORDER TRUE
J 0
(-7990 5350);
DISPLAY 0.638298 (-7990 5350);
PAINT PINK (-7990 5350);
DISPLAY INVISIBLE (-7990 5350);
FORCEPROP 1 LAST COMMENT_BODY TRUE
J 0
(-88 87);
DISPLAY 0.978723 (-88 87);
PAINT GREEN (-88 87);
DISPLAY INVISIBLE (-88 87);
FORCEPROP 2 LAST CUSTOM_TXT_CDS <XR_PAGE_TITLE>
J 0
(-7990 5350);
DISPLAY 0.638298 (-7990 5350);
PAINT PINK (-7990 5350);
DISPLAY INVISIBLE (-7990 5350);
FORCEPROP 2 LAST CDS_XR_PAGE_TITLE CR-7 : @T6G_MB_LIB.T6G(SCH_1):PAGE7
J 0
(-7990 5350);
DISPLAY 0.638298 (-7990 5350);
PAINT PINK (-7990 5350);
DISPLAY INVISIBLE (-7990 5350);
QUIT
